(kicad_pcb
	(version 20260206)
	(generator "pcbnew")
	(generator_version "10.0")
	(general
		(thickness 1.6)
		(legacy_teardrops no)
	)
	(paper "A4")
	(title_block
		(title "Wiwynn_Tioga_Pass_MB.brd")
		(comment 1 "Tioga Pass / footprints 1769-1775 of 4770")
	)
	(layers
		(0 "F.Cu" signal "TOP")
		(4 "In1.Cu" signal "L2GND")
		(6 "In2.Cu" signal "L3")
		(8 "In3.Cu" signal "L4GND")
		(10 "In4.Cu" signal "L5")
		(12 "In5.Cu" signal "L6GND")
		(14 "In6.Cu" signal "L7VCC")
		(16 "In7.Cu" signal "L8VCC")
		(18 "In8.Cu" signal "L9GND")
		(20 "In9.Cu" signal "L10")
		(22 "In10.Cu" signal "L11GND")
		(24 "In11.Cu" signal "L12")
		(26 "In12.Cu" signal "L13GND")
		(2 "B.Cu" signal "BOTTOM")
		(9 "F.Adhes" user "F.Adhesive")
		(11 "B.Adhes" user "B.Adhesive")
		(13 "F.Paste" user "Package Geometry/Pastemask Top")
		(15 "B.Paste" user "Package Geometry/Pastemask Bottom")
		(5 "F.SilkS" user "Ref Des/Silkscreen Top")
		(7 "B.SilkS" user "Ref Des/Silkscreen Bottom")
		(1 "F.Mask" user "Board Geometry/Soldermask Top")
		(3 "B.Mask" user "Board Geometry/Soldermask Bottom")
		(17 "Dwgs.User" user "User.Drawings")
		(19 "Cmts.User" user "User.Comments")
		(21 "Eco1.User" user "User.Eco1")
		(23 "Eco2.User" user "User.Eco2")
		(25 "Edge.Cuts" user "Board Geometry/Outline")
		(27 "Margin" user)
		(31 "F.CrtYd" user "Package Geometry/Place Bound Top")
		(29 "B.CrtYd" user "Package Geometry/Place Bound Bottom")
		(35 "F.Fab" user "Ref Des/Assembly Top")
		(33 "B.Fab" user "Ref Des/Assembly Bottom")
	)
	(footprint ""
		(layer "F.Cu")
		(at 29.6164 -83.963002 -90)
		(property "Reference" "C1D12"
			(at 0 0 270)
			(layer "F.SilkS")
			(hide yes)
			(effects
				(font
					(size 1.27 1.27)
				)
			)
		)
		(property "Value" ""
			(at 0 0 270)
			(layer "F.Fab")
			(effects
				(font
					(size 1.27 1.27)
				)
			)
		)
		(duplicate_pad_numbers_are_jumpers no)
		(fp_rect
			(start 0.3048 -0.1016)
			(end -0.3048 0.9906)
			(stroke
				(width 0)
				(type default)
			)
			(fill no)
			(layer "F.CrtYd")
		)
		(fp_line
			(start -0.3048 0.9906)
			(end 0.3048 0.9906)
			(stroke
				(width 0.1)
				(type default)
			)
			(layer "F.Fab")
		)
		(fp_line
			(start 0.3048 0.9906)
			(end 0.3048 -0.1016)
			(stroke
				(width 0.1)
				(type default)
			)
			(layer "F.Fab")
		)
		(fp_line
			(start -0.3048 -0.1016)
			(end -0.3048 0.9906)
			(stroke
				(width 0.1)
				(type default)
			)
			(layer "F.Fab")
		)
		(fp_line
			(start 0.3048 -0.1016)
			(end -0.3048 -0.1016)
			(stroke
				(width 0.1)
				(type default)
			)
			(layer "F.Fab")
		)
		(pad "1" smd rect
			(at 0 0 270)
			(size 0.508 0.508)
			(layers "F.Cu" "F.Mask" "F.Paste")
			(net "VR_FET_SW_P12V_STBY_PVCCIN_CPU1")
		)
		(pad "2" smd rect
			(at 0 0.889 270)
			(size 0.508 0.508)
			(layers "F.Cu" "F.Mask" "F.Paste")
			(net "GND")
		)
		(zone
			(layer "F.Cu")
			(hatch none 0.5)
			(connect_pads
				(clearance 0)
			)
			(min_thickness 0.25)
			(keepout
				(tracks allowed)
				(vias not_allowed)
				(pads allowed)
				(copperpour not_allowed)
				(footprints allowed)
			)
			(placement
				(enabled no)
				(sheetname "")
			)
			(fill
				(thermal_gap 0.5)
				(thermal_bridge_width 0.5)
				(island_removal_mode 0)
			)
			(polygon
				(pts
					(xy 29.3624 -83.709002) (xy 29.3624 -84.217002) (xy 28.9814 -84.217002) (xy 28.9814 -83.709002)
				)
			)
		)
		(zone
			(layer "F.Cu")
			(hatch none 0.5)
			(connect_pads
				(clearance 0)
			)
			(min_thickness 0.25)
			(keepout
				(tracks not_allowed)
				(vias allowed)
				(pads allowed)
				(copperpour not_allowed)
				(footprints allowed)
			)
			(placement
				(enabled no)
				(sheetname "")
			)
			(fill
				(thermal_gap 0.5)
				(thermal_bridge_width 0.5)
				(island_removal_mode 0)
			)
			(polygon
				(pts
					(xy 29.3624 -83.709002) (xy 29.3624 -84.217002) (xy 28.9814 -84.217002) (xy 28.9814 -83.709002)
				)
			)
		)
	)
	(footprint ""
		(layer "F.Cu")
		(at 417.43122 -111.19612)
		(property "Reference" "R2N1"
			(at 0 0 0)
			(layer "F.SilkS")
			(hide yes)
			(effects
				(font
					(size 1.27 1.27)
				)
			)
		)
		(property "Value" ""
			(at 0 0 0)
			(layer "F.Fab")
			(effects
				(font
					(size 1.27 1.27)
				)
			)
		)
		(duplicate_pad_numbers_are_jumpers no)
		(fp_poly
			(pts
				(xy -0.2794 -0.1016) (xy 0.2794 -0.1016) (xy 0.2794 0.9906) (xy -0.2794 0.9906)
			)
			(stroke
				(width 0)
				(type default)
			)
			(fill no)
			(layer "F.CrtYd")
		)
		(fp_line
			(start -0.2794 -0.1016)
			(end -0.2794 0.9906)
			(stroke
				(width 0.1)
				(type default)
			)
			(layer "F.Fab")
		)
		(fp_line
			(start -0.2794 0.9906)
			(end 0.2794 0.9906)
			(stroke
				(width 0.1)
				(type default)
			)
			(layer "F.Fab")
		)
		(fp_line
			(start 0.2794 -0.1016)
			(end -0.2794 -0.1016)
			(stroke
				(width 0.1)
				(type default)
			)
			(layer "F.Fab")
		)
		(fp_line
			(start 0.2794 0.9906)
			(end 0.2794 -0.1016)
			(stroke
				(width 0.1)
				(type default)
			)
			(layer "F.Fab")
		)
		(pad "1" smd rect
			(at 0 0)
			(size 0.508 0.508)
			(layers "F.Cu" "F.Mask" "F.Paste")
			(net "FM_CPU_CATERR_DLY_LVT3_R_N")
		)
		(pad "2" smd rect
			(at 0 0.889)
			(size 0.508 0.508)
			(layers "F.Cu" "F.Mask" "F.Paste")
			(net "FM_CPU_CATERR_DLY_LVT3_N")
		)
		(zone
			(layer "F.Cu")
			(hatch none 0.5)
			(connect_pads
				(clearance 0)
			)
			(min_thickness 0.25)
			(keepout
				(tracks allowed)
				(vias not_allowed)
				(pads allowed)
				(copperpour not_allowed)
				(footprints allowed)
			)
			(placement
				(enabled no)
				(sheetname "")
			)
			(fill
				(thermal_gap 0.5)
				(thermal_bridge_width 0.5)
				(island_removal_mode 0)
			)
			(polygon
				(pts
					(xy 417.17722 -110.94212) (xy 417.68522 -110.94212) (xy 417.68522 -110.56112) (xy 417.17722 -110.56112)
				)
			)
		)
		(zone
			(layer "F.Cu")
			(hatch none 0.5)
			(connect_pads
				(clearance 0)
			)
			(min_thickness 0.25)
			(keepout
				(tracks not_allowed)
				(vias allowed)
				(pads allowed)
				(copperpour not_allowed)
				(footprints allowed)
			)
			(placement
				(enabled no)
				(sheetname "")
			)
			(fill
				(thermal_gap 0.5)
				(thermal_bridge_width 0.5)
				(island_removal_mode 0)
			)
			(polygon
				(pts
					(xy 417.17722 -110.56112) (xy 417.68522 -110.56112) (xy 417.68522 -110.94212) (xy 417.17722 -110.94212)
				)
			)
		)
	)
	(footprint ""
		(layer "F.Cu")
		(at 192.786 -23.396194)
		(property "Reference" "R4F3"
			(at 0 0 0)
			(layer "F.SilkS")
			(hide yes)
			(effects
				(font
					(size 1.27 1.27)
				)
			)
		)
		(property "Value" ""
			(at 0 0 0)
			(layer "F.Fab")
			(effects
				(font
					(size 1.27 1.27)
				)
			)
		)
		(duplicate_pad_numbers_are_jumpers no)
		(fp_poly
			(pts
				(xy -0.2794 -0.1016) (xy 0.2794 -0.1016) (xy 0.2794 0.9906) (xy -0.2794 0.9906)
			)
			(stroke
				(width 0)
				(type default)
			)
			(fill no)
			(layer "F.CrtYd")
		)
		(fp_line
			(start -0.2794 -0.1016)
			(end -0.2794 0.9906)
			(stroke
				(width 0.1)
				(type default)
			)
			(layer "F.Fab")
		)
		(fp_line
			(start -0.2794 0.9906)
			(end 0.2794 0.9906)
			(stroke
				(width 0.1)
				(type default)
			)
			(layer "F.Fab")
		)
		(fp_line
			(start 0.2794 -0.1016)
			(end -0.2794 -0.1016)
			(stroke
				(width 0.1)
				(type default)
			)
			(layer "F.Fab")
		)
		(fp_line
			(start 0.2794 0.9906)
			(end 0.2794 -0.1016)
			(stroke
				(width 0.1)
				(type default)
			)
			(layer "F.Fab")
		)
		(pad "1" smd rect
			(at 0 0)
			(size 0.508 0.508)
			(layers "F.Cu" "F.Mask" "F.Paste")
			(net "M_A_CPU_VREF")
		)
		(pad "2" smd rect
			(at 0 0.889)
			(size 0.508 0.508)
			(layers "F.Cu" "F.Mask" "F.Paste")
			(net "M_A_VREF")
		)
		(zone
			(layer "F.Cu")
			(hatch none 0.5)
			(connect_pads
				(clearance 0)
			)
			(min_thickness 0.25)
			(keepout
				(tracks allowed)
				(vias not_allowed)
				(pads allowed)
				(copperpour not_allowed)
				(footprints allowed)
			)
			(placement
				(enabled no)
				(sheetname "")
			)
			(fill
				(thermal_gap 0.5)
				(thermal_bridge_width 0.5)
				(island_removal_mode 0)
			)
			(polygon
				(pts
					(xy 192.532 -23.142194) (xy 193.04 -23.142194) (xy 193.04 -22.761194) (xy 192.532 -22.761194)
				)
			)
		)
		(zone
			(layer "F.Cu")
			(hatch none 0.5)
			(connect_pads
				(clearance 0)
			)
			(min_thickness 0.25)
			(keepout
				(tracks not_allowed)
				(vias allowed)
				(pads allowed)
				(copperpour not_allowed)
				(footprints allowed)
			)
			(placement
				(enabled no)
				(sheetname "")
			)
			(fill
				(thermal_gap 0.5)
				(thermal_bridge_width 0.5)
				(island_removal_mode 0)
			)
			(polygon
				(pts
					(xy 192.532 -22.761194) (xy 193.04 -22.761194) (xy 193.04 -23.142194) (xy 192.532 -23.142194)
				)
			)
		)
	)
	(footprint ""
		(layer "F.Cu")
		(at 398.879568 -34.279586 90)
		(property "Reference" "R8G6"
			(at 0 0 90)
			(layer "F.SilkS")
			(hide yes)
			(effects
				(font
					(size 1.27 1.27)
				)
			)
		)
		(property "Value" ""
			(at 0 0 90)
			(layer "F.Fab")
			(effects
				(font
					(size 1.27 1.27)
				)
			)
		)
		(duplicate_pad_numbers_are_jumpers no)
		(fp_poly
			(pts
				(xy -0.2794 -0.1016) (xy 0.2794 -0.1016) (xy 0.2794 0.9906) (xy -0.2794 0.9906)
			)
			(stroke
				(width 0)
				(type default)
			)
			(fill no)
			(layer "F.CrtYd")
		)
		(fp_line
			(start 0.2794 -0.1016)
			(end -0.2794 -0.1016)
			(stroke
				(width 0.1)
				(type default)
			)
			(layer "F.Fab")
		)
		(fp_line
			(start -0.2794 -0.1016)
			(end -0.2794 0.9906)
			(stroke
				(width 0.1)
				(type default)
			)
			(layer "F.Fab")
		)
		(fp_line
			(start 0.2794 0.9906)
			(end 0.2794 -0.1016)
			(stroke
				(width 0.1)
				(type default)
			)
			(layer "F.Fab")
		)
		(fp_line
			(start -0.2794 0.9906)
			(end 0.2794 0.9906)
			(stroke
				(width 0.1)
				(type default)
			)
			(layer "F.Fab")
		)
		(pad "1" smd rect
			(at 0 0 90)
			(size 0.508 0.508)
			(layers "F.Cu" "F.Mask" "F.Paste")
			(net "P3V3_STBY")
		)
		(pad "2" smd rect
			(at 0 0.889 90)
			(size 0.508 0.508)
			(layers "F.Cu" "F.Mask" "F.Paste")
			(net "SMB_OCP_LAN_STBY_LVC3_SDA_R")
		)
		(zone
			(layer "F.Cu")
			(hatch none 0.5)
			(connect_pads
				(clearance 0)
			)
			(min_thickness 0.25)
			(keepout
				(tracks allowed)
				(vias not_allowed)
				(pads allowed)
				(copperpour not_allowed)
				(footprints allowed)
			)
			(placement
				(enabled no)
				(sheetname "")
			)
			(fill
				(thermal_gap 0.5)
				(thermal_bridge_width 0.5)
				(island_removal_mode 0)
			)
			(polygon
				(pts
					(xy 399.133568 -34.025586) (xy 399.133568 -34.533586) (xy 399.514568 -34.533586) (xy 399.514568 -34.025586)
				)
			)
		)
		(zone
			(layer "F.Cu")
			(hatch none 0.5)
			(connect_pads
				(clearance 0)
			)
			(min_thickness 0.25)
			(keepout
				(tracks not_allowed)
				(vias allowed)
				(pads allowed)
				(copperpour not_allowed)
				(footprints allowed)
			)
			(placement
				(enabled no)
				(sheetname "")
			)
			(fill
				(thermal_gap 0.5)
				(thermal_bridge_width 0.5)
				(island_removal_mode 0)
			)
			(polygon
				(pts
					(xy 399.514568 -34.025586) (xy 399.514568 -34.533586) (xy 399.133568 -34.533586) (xy 399.133568 -34.025586)
				)
			)
		)
	)
	(footprint ""
		(layer "F.Cu")
		(at 30.554168 -128.8542 90)
		(property "Reference" "C1B9"
			(at 0 0 90)
			(layer "F.SilkS")
			(hide yes)
			(effects
				(font
					(size 1.27 1.27)
				)
			)
		)
		(property "Value" ""
			(at 0 0 90)
			(layer "F.Fab")
			(effects
				(font
					(size 1.27 1.27)
				)
			)
		)
		(duplicate_pad_numbers_are_jumpers no)
		(fp_poly
			(pts
				(xy 0.3048 -0.1016) (xy 0.3048 0.9906) (xy -0.3048 0.9906) (xy -0.3048 -0.1016)
			)
			(stroke
				(width 0)
				(type default)
			)
			(fill no)
			(layer "F.CrtYd")
		)
		(fp_line
			(start 0.3048 -0.1016)
			(end -0.3048 -0.1016)
			(stroke
				(width 0.1)
				(type default)
			)
			(layer "F.Fab")
		)
		(fp_line
			(start -0.3048 -0.1016)
			(end -0.3048 0.9906)
			(stroke
				(width 0.1)
				(type default)
			)
			(layer "F.Fab")
		)
		(fp_line
			(start 0.3048 0.9906)
			(end 0.3048 -0.1016)
			(stroke
				(width 0.1)
				(type default)
			)
			(layer "F.Fab")
		)
		(fp_line
			(start -0.3048 0.9906)
			(end 0.3048 0.9906)
			(stroke
				(width 0.1)
				(type default)
			)
			(layer "F.Fab")
		)
		(pad "1" smd rect
			(at 0 0 90)
			(size 0.508 0.508)
			(layers "F.Cu" "F.Mask" "F.Paste")
			(net "M_K_VREF")
		)
		(pad "2" smd rect
			(at 0 0.889 90)
			(size 0.508 0.508)
			(layers "F.Cu" "F.Mask" "F.Paste")
			(net "GND")
		)
		(zone
			(layer "F.Cu")
			(hatch none 0.5)
			(connect_pads
				(clearance 0)
			)
			(min_thickness 0.25)
			(keepout
				(tracks allowed)
				(vias not_allowed)
				(pads allowed)
				(copperpour not_allowed)
				(footprints allowed)
			)
			(placement
				(enabled no)
				(sheetname "")
			)
			(fill
				(thermal_gap 0.5)
				(thermal_bridge_width 0.5)
				(island_removal_mode 0)
			)
			(polygon
				(pts
					(xy 30.808168 -128.6002) (xy 30.808168 -129.1082) (xy 31.189168 -129.1082) (xy 31.189168 -128.6002)
				)
			)
		)
		(zone
			(layer "F.Cu")
			(hatch none 0.5)
			(connect_pads
				(clearance 0)
			)
			(min_thickness 0.25)
			(keepout
				(tracks not_allowed)
				(vias allowed)
				(pads allowed)
				(copperpour not_allowed)
				(footprints allowed)
			)
			(placement
				(enabled no)
				(sheetname "")
			)
			(fill
				(thermal_gap 0.5)
				(thermal_bridge_width 0.5)
				(island_removal_mode 0)
			)
			(polygon
				(pts
					(xy 31.189168 -128.6002) (xy 31.189168 -129.1082) (xy 30.808168 -129.1082) (xy 30.808168 -128.6002)
				)
			)
		)
	)
	(footprint ""
		(layer "F.Cu")
		(at 32.6263 -32.9438)
		(property "Reference" "R1F3"
			(at -0.90297 -2.159 270)
			(unlocked yes)
			(layer "F.SilkS")
			(effects
				(font
					(size 0.7874 0.5842)
					(thickness 0.1524)
				)
			)
		)
		(property "Value" ""
			(at 0 0 0)
			(layer "F.Fab")
			(effects
				(font
					(size 1.27 1.27)
				)
			)
		)
		(duplicate_pad_numbers_are_jumpers no)
		(fp_line
			(start -0.9017 1.951736)
			(end -0.9017 0.823468)
			(stroke
				(width 0.1524)
				(type default)
			)
			(layer "F.SilkS")
		)
		(fp_line
			(start 0.9017 1.952498)
			(end 0.9017 0.853948)
			(stroke
				(width 0.1524)
				(type default)
			)
			(layer "F.SilkS")
		)
		(fp_rect
			(start 0.9017 -0.3048)
			(end -0.9017 3.0988)
			(stroke
				(width 0)
				(type default)
			)
			(fill no)
			(layer "F.CrtYd")
		)
		(fp_line
			(start -0.9017 -0.3048)
			(end -0.9017 3.0988)
			(stroke
				(width 0.1)
				(type default)
			)
			(layer "F.Fab")
		)
		(fp_line
			(start -0.9017 3.0988)
			(end 0.9017 3.0988)
			(stroke
				(width 0.1)
				(type default)
			)
			(layer "F.Fab")
		)
		(fp_line
			(start 0.9017 -0.3048)
			(end -0.9017 -0.3048)
			(stroke
				(width 0.1)
				(type default)
			)
			(layer "F.Fab")
		)
		(fp_line
			(start 0.9017 3.0988)
			(end 0.9017 -0.3048)
			(stroke
				(width 0.1)
				(type default)
			)
			(layer "F.Fab")
		)
		(pad "1" smd rect
			(at 0 0)
			(size 1.524 1.016)
			(layers "F.Cu" "F.Mask" "F.Paste")
			(net "P12V_STBY")
		)
		(pad "2" smd rect
			(at 0 2.794)
			(size 1.524 1.016)
			(layers "F.Cu" "F.Mask" "F.Paste")
			(net "P12V_NVDIMM_GHJ")
		)
		(zone
			(layer "F.Cu")
			(hatch none 0.5)
			(connect_pads
				(clearance 0)
			)
			(min_thickness 0.25)
			(keepout
				(tracks allowed)
				(vias not_allowed)
				(pads allowed)
				(copperpour not_allowed)
				(footprints allowed)
			)
			(placement
				(enabled no)
				(sheetname "")
			)
			(fill
				(thermal_gap 0.5)
				(thermal_bridge_width 0.5)
				(island_removal_mode 0)
			)
			(polygon
				(pts
					(xy 33.3883 -32.4358) (xy 31.8643 -32.4358) (xy 31.8643 -30.6578) (xy 33.3883 -30.6578)
				)
			)
		)
	)
	(footprint ""
		(layer "F.Cu")
		(at 435.5338 -15.748)
		(property "Reference" "R6W46"
			(at -0.8382 -0.67818 0)
			(unlocked yes)
			(layer "F.SilkS")
			(effects
				(font
					(size 0.4064 0.254)
					(thickness 0.1524)
				)
				(justify left)
			)
		)
		(property "Value" ""
			(at 0 0 0)
			(layer "F.Fab")
			(effects
				(font
					(size 1.27 1.27)
				)
			)
		)
		(duplicate_pad_numbers_are_jumpers no)
		(fp_poly
			(pts
				(xy -0.2794 -0.1016) (xy 0.2794 -0.1016) (xy 0.2794 0.9906) (xy -0.2794 0.9906)
			)
			(stroke
				(width 0)
				(type default)
			)
			(fill no)
			(layer "F.CrtYd")
		)
		(fp_line
			(start -0.2794 -0.1016)
			(end -0.2794 0.9906)
			(stroke
				(width 0.1)
				(type default)
			)
			(layer "F.Fab")
		)
		(fp_line
			(start -0.2794 0.9906)
			(end 0.2794 0.9906)
			(stroke
				(width 0.1)
				(type default)
			)
			(layer "F.Fab")
		)
		(fp_line
			(start 0.2794 -0.1016)
			(end -0.2794 -0.1016)
			(stroke
				(width 0.1)
				(type default)
			)
			(layer "F.Fab")
		)
		(fp_line
			(start 0.2794 0.9906)
			(end 0.2794 -0.1016)
			(stroke
				(width 0.1)
				(type default)
			)
			(layer "F.Fab")
		)
		(pad "1" smd rect
			(at 0 0)
			(size 0.508 0.508)
			(layers "F.Cu" "F.Mask" "F.Paste")
			(net "PCA9554_A1")
		)
		(pad "2" smd rect
			(at 0 0.889)
			(size 0.508 0.508)
			(layers "F.Cu" "F.Mask" "F.Paste")
			(net "GND")
		)
		(zone
			(layer "F.Cu")
			(hatch none 0.5)
			(connect_pads
				(clearance 0)
			)
			(min_thickness 0.25)
			(keepout
				(tracks allowed)
				(vias not_allowed)
				(pads allowed)
				(copperpour not_allowed)
				(footprints allowed)
			)
			(placement
				(enabled no)
				(sheetname "")
			)
			(fill
				(thermal_gap 0.5)
				(thermal_bridge_width 0.5)
				(island_removal_mode 0)
			)
			(polygon
				(pts
					(xy 435.2798 -15.494) (xy 435.7878 -15.494) (xy 435.7878 -15.113) (xy 435.2798 -15.113)
				)
			)
		)
		(zone
			(layer "F.Cu")
			(hatch none 0.5)
			(connect_pads
				(clearance 0)
			)
			(min_thickness 0.25)
			(keepout
				(tracks not_allowed)
				(vias allowed)
				(pads allowed)
				(copperpour not_allowed)
				(footprints allowed)
			)
			(placement
				(enabled no)
				(sheetname "")
			)
			(fill
				(thermal_gap 0.5)
				(thermal_bridge_width 0.5)
				(island_removal_mode 0)
			)
			(polygon
				(pts
					(xy 435.2798 -15.113) (xy 435.7878 -15.113) (xy 435.7878 -15.494) (xy 435.2798 -15.494)
				)
			)
		)
	)
)
